# BASEBOARD_FAB2 (Tioga Pass) — schematic netlist excerpt (pin names and nets, part order shuffled) for the footprints in the layout excerpt that follows; sources: Cadence DE-HDL packaged netlist, KiCad conversion of Wiwynn_Tioga_Pass_MB.brd

R2W3  RES  0.0 5% CHIP  pkg 0402  page 119 : A = FM_PMBUS_ALERT_BUF_EN_R_N ; B = FM_PMBUS_ALERT_BUF_EN_N
C3N25  CAP_A  1.0UF 6.3V 10% X6S  pkg 0402V  page 130 : A = P1V8_PCH_STBY ; B = GND

(kicad_pcb
	(version 20260206)
	(generator "pcbnew")
	(generator_version "10.0")
	(general
		(thickness 1.6)
		(legacy_teardrops no)
	)
	(paper "A4")
	(title_block
		(title "Wiwynn_Tioga_Pass_MB.brd")
		(comment 1 "Tioga Pass / footprints 2790-2791 of 4770")
	)
	(layers
		(0 "F.Cu" signal "TOP")
		(4 "In1.Cu" signal "L2GND")
		(6 "In2.Cu" signal "L3")
		(8 "In3.Cu" signal "L4GND")
		(10 "In4.Cu" signal "L5")
		(12 "In5.Cu" signal "L6GND")
		(14 "In6.Cu" signal "L7VCC")
		(16 "In7.Cu" signal "L8VCC")
		(18 "In8.Cu" signal "L9GND")
		(20 "In9.Cu" signal "L10")
		(22 "In10.Cu" signal "L11GND")
		(24 "In11.Cu" signal "L12")
		(26 "In12.Cu" signal "L13GND")
		(2 "B.Cu" signal "BOTTOM")
		(9 "F.Adhes" user "F.Adhesive")
		(11 "B.Adhes" user "B.Adhesive")
		(13 "F.Paste" user "Package Geometry/Pastemask Top")
		(15 "B.Paste" user "Package Geometry/Pastemask Bottom")
		(5 "F.SilkS" user "Ref Des/Silkscreen Top")
		(7 "B.SilkS" user "Ref Des/Silkscreen Bottom")
		(1 "F.Mask" user "Board Geometry/Soldermask Top")
		(3 "B.Mask" user "Board Geometry/Soldermask Bottom")
		(17 "Dwgs.User" user "User.Drawings")
		(19 "Cmts.User" user "User.Comments")
		(21 "Eco1.User" user "User.Eco1")
		(23 "Eco2.User" user "User.Eco2")
		(25 "Edge.Cuts" user "Board Geometry/Outline")
		(27 "Margin" user)
		(31 "F.CrtYd" user "Package Geometry/Place Bound Top")
		(29 "B.CrtYd" user "Package Geometry/Place Bound Bottom")
		(35 "F.Fab" user "Ref Des/Assembly Top")
		(33 "B.Fab" user "Ref Des/Assembly Bottom")
	)
	(footprint ""
		(layer "B.Cu")
		(at 392.692128 -88.314784 90)
		(property "Reference" "R2W3"
			(at 0.8382 -0.67818 90)
			(unlocked yes)
			(layer "B.SilkS")
			(effects
				(font
					(size 0.4064 0.254)
					(thickness 0.1524)
				)
				(justify left mirror)
			)
		)
		(property "Value" ""
			(at 0 0 90)
			(layer "B.Fab")
			(effects
				(font
					(size 1.27 1.27)
				)
				(justify mirror)
			)
		)
		(duplicate_pad_numbers_are_jumpers no)
		(fp_poly
			(pts
				(xy 0.2794 -0.1016) (xy -0.2794 -0.1016) (xy -0.2794 0.9906) (xy 0.2794 0.9906)
			)
			(stroke
				(width 0)
				(type default)
			)
			(fill no)
			(layer "B.CrtYd")
		)
		(fp_line
			(start 0.2794 -0.1016)
			(end 0.2794 0.9906)
			(stroke
				(width 0.1)
				(type default)
			)
			(layer "B.Fab")
		)
		(fp_line
			(start -0.2794 -0.1016)
			(end 0.2794 -0.1016)
			(stroke
				(width 0.1)
				(type default)
			)
			(layer "B.Fab")
		)
		(fp_line
			(start 0.2794 0.9906)
			(end -0.2794 0.9906)
			(stroke
				(width 0.1)
				(type default)
			)
			(layer "B.Fab")
		)
		(fp_line
			(start -0.2794 0.9906)
			(end -0.2794 -0.1016)
			(stroke
				(width 0.1)
				(type default)
			)
			(layer "B.Fab")
		)
		(pad "1" smd rect
			(at 0 0 270)
			(size 0.508 0.508)
			(layers "B.Cu" "B.Mask" "B.Paste")
			(net "FM_PMBUS_ALERT_BUF_EN_R_N")
		)
		(pad "2" smd rect
			(at 0 0.889 270)
			(size 0.508 0.508)
			(layers "B.Cu" "B.Mask" "B.Paste")
			(net "FM_PMBUS_ALERT_BUF_EN_N")
		)
		(zone
			(layer "B.Cu")
			(hatch none 0.5)
			(connect_pads
				(clearance 0)
			)
			(min_thickness 0.25)
			(keepout
				(tracks allowed)
				(vias not_allowed)
				(pads allowed)
				(copperpour not_allowed)
				(footprints allowed)
			)
			(placement
				(enabled no)
				(sheetname "")
			)
			(fill
				(thermal_gap 0.5)
				(thermal_bridge_width 0.5)
				(island_removal_mode 0)
			)
			(polygon
				(pts
					(xy 392.946128 -88.568784) (xy 392.946128 -88.060784) (xy 393.327128 -88.060784) (xy 393.327128 -88.568784)
				)
			)
		)
		(zone
			(layer "B.Cu")
			(hatch none 0.5)
			(connect_pads
				(clearance 0)
			)
			(min_thickness 0.25)
			(keepout
				(tracks not_allowed)
				(vias allowed)
				(pads allowed)
				(copperpour not_allowed)
				(footprints allowed)
			)
			(placement
				(enabled no)
				(sheetname "")
			)
			(fill
				(thermal_gap 0.5)
				(thermal_bridge_width 0.5)
				(island_removal_mode 0)
			)
			(polygon
				(pts
					(xy 393.327128 -88.568784) (xy 393.327128 -88.060784) (xy 392.946128 -88.060784) (xy 392.946128 -88.568784)
				)
			)
		)
	)
	(footprint ""
		(layer "B.Cu")
		(at 386.1816 -104.5464 90)
		(property "Reference" "C3N25"
			(at 0 0 90)
			(layer "B.SilkS")
			(hide yes)
			(effects
				(font
					(size 1.27 1.27)
				)
				(justify mirror)
			)
		)
		(property "Value" ""
			(at 0 0 90)
			(layer "B.Fab")
			(effects
				(font
					(size 1.27 1.27)
				)
				(justify mirror)
			)
		)
		(duplicate_pad_numbers_are_jumpers no)
		(fp_rect
			(start 0.2794 0.9144)
			(end -0.2794 -0.1143)
			(stroke
				(width 0)
				(type default)
			)
			(fill no)
			(layer "B.CrtYd")
		)
		(fp_line
			(start 0.2794 -0.1143)
			(end -0.2794 -0.1143)
			(stroke
				(width 0.1)
				(type default)
			)
			(layer "B.Fab")
		)
		(fp_line
			(start -0.2794 -0.1143)
			(end -0.2794 0.9144)
			(stroke
				(width 0.1)
				(type default)
			)
			(layer "B.Fab")
		)
		(fp_line
			(start 0.2794 0.9144)
			(end 0.2794 -0.1143)
			(stroke
				(width 0.1)
				(type default)
			)
			(layer "B.Fab")
		)
		(fp_line
			(start -0.2794 0.9144)
			(end 0.2794 0.9144)
			(stroke
				(width 0.1)
				(type default)
			)
			(layer "B.Fab")
		)
		(pad "1" smd custom
			(at 0 0)
			(size 0.10414 0.10414)
			(layers "B.Cu" "B.Mask" "B.Paste")
			(net "P1V8_PCH_STBY")
			(options
				(clearance outline)
				(anchor circle)
			)
			(primitives
				(gr_poly
					(pts
						(xy -0.20828 -0.08636) (xy -0.20828 0.08636) (xy -0.08636 0.20828) (xy 0.086614 0.20828) (xy 0.20828 0.086614)
						(xy 0.20828 -0.08636) (xy 0.08636 -0.20828) (xy -0.08636 -0.20828)
					)
					(width 0)
					(fill yes)
				)
			)
		)
		(pad "2" smd custom
			(at 0 0.8001)
			(size 0.10414 0.10414)
			(layers "B.Cu" "B.Mask" "B.Paste")
			(net "GND")
			(options
				(clearance outline)
				(anchor circle)
			)
			(primitives
				(gr_poly
					(pts
						(xy -0.20828 -0.08636) (xy -0.20828 0.08636) (xy -0.08636 0.20828) (xy 0.086614 0.20828) (xy 0.20828 0.086614)
						(xy 0.20828 -0.08636) (xy 0.08636 -0.20828) (xy -0.08636 -0.20828)
					)
					(width 0)
					(fill yes)
				)
			)
		)
		(zone
			(layer "B.Cu")
			(hatch none 0.5)
			(connect_pads
				(clearance 0)
			)
			(min_thickness 0.25)
			(keepout
				(tracks not_allowed)
				(vias allowed)
				(pads allowed)
				(copperpour not_allowed)
				(footprints allowed)
			)
			(placement
				(enabled no)
				(sheetname "")
			)
			(fill
				(thermal_gap 0.5)
				(thermal_bridge_width 0.5)
				(island_removal_mode 0)
			)
			(polygon
				(pts
					(xy 386.39115 -104.63403) (xy 386.77215 -104.63403) (xy 386.77215 -104.45877) (xy 386.39115 -104.458516)
				)
			)
		)
		(zone
			(layer "B.Cu")
			(hatch none 0.5)
			(connect_pads
				(clearance 0)
			)
			(min_thickness 0.25)
			(keepout
				(tracks allowed)
				(vias not_allowed)
				(pads allowed)
				(copperpour not_allowed)
				(footprints allowed)
			)
			(placement
				(enabled no)
				(sheetname "")
			)
			(fill
				(thermal_gap 0.5)
				(thermal_bridge_width 0.5)
				(island_removal_mode 0)
			)
			(polygon
				(pts
					(xy 386.39115 -104.63403) (xy 386.77215 -104.63403) (xy 386.77215 -104.45877) (xy 386.39115 -104.458516)
				)
			)
		)
	)
)
